(kicad_pcb
	(version 20241229)
	(generator "pcbnew")
	(generator_version "9.0")
	(general
		(thickness 1.294)
		(legacy_teardrops no)
	)
	(paper "A3")
	(title_block
		(title "Kintex 410T devboard")
		(date "2024-04-03")
		(rev "1.1.2")
		(comment 9 "footprint 170 of 975 (U1), pads 63-122 of 900")
	)
	(layers
		(0 "F.Cu" mixed)
		(4 "In1.Cu" power)
		(6 "In2.Cu" power)
		(8 "In3.Cu" mixed)
		(10 "In4.Cu" power)
		(12 "In5.Cu" mixed)
		(14 "In6.Cu" power)
		(16 "In7.Cu" mixed)
		(18 "In8.Cu" power)
		(2 "B.Cu" mixed)
		(9 "F.Adhes" user "F.Adhesive")
		(11 "B.Adhes" user "B.Adhesive")
		(13 "F.Paste" user)
		(15 "B.Paste" user)
		(5 "F.SilkS" user "F.Silkscreen")
		(7 "B.SilkS" user "B.Silkscreen")
		(1 "F.Mask" user)
		(3 "B.Mask" user)
		(17 "Dwgs.User" user "User.Drawings")
		(19 "Cmts.User" user "User.Comments")
		(21 "Eco1.User" user "User.Eco1")
		(23 "Eco2.User" user "User.Eco2")
		(25 "Edge.Cuts" user)
		(27 "Margin" user)
		(31 "F.CrtYd" user "F.Courtyard")
		(29 "B.CrtYd" user "B.Courtyard")
		(35 "F.Fab" user)
		(33 "B.Fab" user)
	)
	(footprint "antmicro-footprints:BGA-900_31x31mm_Layout30x30_P1x1mm_FFG900"
		(locked yes)
		(layer "F.Cu")
		(at 200 130)
		(property "Reference" "U1"
			(at -15.74 -15.78 0)
			(layer "F.SilkS")
			(effects
				(font
					(size 0.7 0.7)
					(thickness 0.15)
				)
				(justify left bottom)
			)
		)
		(property "Value" "XC7K410T-2FFG900I"
			(at -4.436 17.635 0)
			(layer "F.Fab")
			(effects
				(font
					(size 0.7 0.7)
					(thickness 0.15)
				)
				(justify left bottom)
			)
		)
		(property "Description" "FPGA, Kintex-7, MMCM, PLL, 350 I/O's, 710 MHz, 406720 Cells, 970 mV to 1.03 V, FCBGA-900"
			(at 0 0 0)
			(layer "F.Fab")
			(hide yes)
			(effects
				(font
					(size 1.27 1.27)
					(thickness 0.15)
				)
			)
		)
		(property "Author" "Antmicro"
			(at 0 0 0)
			(layer "F.Fab")
			(hide yes)
			(effects
				(font
					(size 1 1)
					(thickness 0.15)
				)
			)
		)
		(property "License" "Apache-2.0"
			(at 0 0 0)
			(layer "F.Fab")
			(hide yes)
			(effects
				(font
					(size 1 1)
					(thickness 0.15)
				)
			)
		)
		(property "MPN" "XC7K410T-2FFG900I"
			(at 0 0 0)
			(layer "F.Fab")
			(hide yes)
			(effects
				(font
					(size 1 1)
					(thickness 0.15)
				)
			)
		)
		(property "Manufacturer" "AMD-Xilinx"
			(at 0 0 0)
			(layer "F.Fab")
			(hide yes)
			(effects
				(font
					(size 1 1)
					(thickness 0.15)
				)
			)
		)
		(sheetname "FPGA supply")
		(sheetfile "fpga-supply.kicad_sch")
		(attr smd)
		(pad "AB3" smd circle
			(at -12.5 6.5)
			(size 0.5 0.5)
			(property pad_prop_bga)
			(layers "F.Cu" "F.Mask" "F.Paste")
			(net 1 "GND")
			(pinfunction "GND")
			(pintype "passive")
			(solder_mask_margin 0.02)
		)
		(pad "AB4" smd circle
			(at -11.5 6.5)
			(size 0.5 0.5)
			(property pad_prop_bga)
			(layers "F.Cu" "F.Mask" "F.Paste")
			(net 1 "GND")
			(pinfunction "GND")
			(pintype "passive")
			(solder_mask_margin 0.02)
		)
		(pad "AB5" smd circle
			(at -10.5 6.5)
			(size 0.5 0.5)
			(property pad_prop_bga)
			(layers "F.Cu" "F.Mask" "F.Paste")
			(net 300 "/FPGA Config/MODE0")
			(pinfunction "M0_0")
			(pintype "bidirectional")
			(die_length 23.349)
			(solder_mask_margin 0.02)
		)
		(pad "AB6" smd circle
			(at -9.5 6.5)
			(size 0.5 0.5)
			(property pad_prop_bga)
			(layers "F.Cu" "F.Mask" "F.Paste")
			(net 24 "+3V3")
			(pinfunction "VCCO_0")
			(pintype "bidirectional")
			(solder_mask_margin 0.02)
		)
		(pad "AB7" smd circle
			(at -8.5 6.5)
			(size 0.5 0.5)
			(property pad_prop_bga)
			(layers "F.Cu" "F.Mask" "F.Paste")
			(net 568 "/FPGA Bank 33 & 34/DDR_VRP")
			(pinfunction "IO_25_VRP_34")
			(pintype "bidirectional")
			(die_length 13.149)
			(solder_mask_margin 0.02)
		)
		(pad "AB8" smd circle
			(at -7.5 6.5)
			(size 0.5 0.5)
			(property pad_prop_bga)
			(layers "F.Cu" "F.Mask" "F.Paste")
			(net 1310 "/USER_IO.DIP_SW1")
			(pinfunction "IO_L2N_T0_33")
			(pintype "bidirectional")
			(die_length 15.354)
			(solder_mask_margin 0.02)
		)
		(pad "AB9" smd circle
			(at -6.5 6.5)
			(size 0.5 0.5)
			(property pad_prop_bga)
			(layers "F.Cu" "F.Mask" "F.Paste")
			(net 1320 "/USER_IO.DIP_SW6")
			(pinfunction "IO_L3P_T0_DQS_33")
			(pintype "bidirectional")
			(die_length 11.874)
			(solder_mask_margin 0.02)
		)
		(pad "AB10" smd circle
			(at -5.5 6.5)
			(size 0.5 0.5)
			(property pad_prop_bga)
			(layers "F.Cu" "F.Mask" "F.Paste")
			(net 391 "/FPGA Bank 33 & 34/SD_CARD.DAT3")
			(pinfunction "IO_L7P_T1_33")
			(pintype "bidirectional")
			(die_length 11.514)
			(solder_mask_margin 0.02)
		)
		(pad "AB11" smd circle
			(at -4.5 6.5)
			(size 0.5 0.5)
			(property pad_prop_bga)
			(layers "F.Cu" "F.Mask" "F.Paste")
			(net 1 "GND")
			(pinfunction "GND")
			(pintype "passive")
			(solder_mask_margin 0.02)
		)
		(pad "AB12" smd circle
			(at -3.5 6.5)
			(size 0.5 0.5)
			(property pad_prop_bga)
			(layers "F.Cu" "F.Mask" "F.Paste")
			(net 399 "unconnected-(U1E-IO_L1N_T0_33-PadAB12)")
			(pinfunction "IO_L1N_T0_33")
			(pintype "bidirectional+no_connect")
			(die_length 9.344)
			(solder_mask_margin 0.02)
		)
		(pad "AB13" smd circle
			(at -2.5 6.5)
			(size 0.5 0.5)
			(property pad_prop_bga)
			(layers "F.Cu" "F.Mask" "F.Paste")
			(net 1322 "/USER_IO.DIP_SW5")
			(pinfunction "IO_L6N_T0_VREF_33")
			(pintype "bidirectional")
			(die_length 8.095)
			(solder_mask_margin 0.02)
		)
		(pad "AB14" smd circle
			(at -1.5 6.5)
			(size 0.5 0.5)
			(property pad_prop_bga)
			(layers "F.Cu" "F.Mask" "F.Paste")
			(net 586 "unconnected-(U1D-IO_25_VRP_32-PadAB14)")
			(pinfunction "IO_25_VRP_32")
			(pintype "bidirectional+no_connect")
			(die_length 11.456)
			(solder_mask_margin 0.02)
		)
		(pad "AB15" smd circle
			(at -0.5 6.5)
			(size 0.5 0.5)
			(property pad_prop_bga)
			(layers "F.Cu" "F.Mask" "F.Paste")
			(net 587 "/FPGA Bank 12 & 13/USB_USER.RCV")
			(pinfunction "IO_L20N_T3_32")
			(pintype "bidirectional")
			(die_length 11.928)
			(solder_mask_margin 0.02)
		)
		(pad "AB16" smd circle
			(at 0.5 6.5)
			(size 0.5 0.5)
			(property pad_prop_bga)
			(layers "F.Cu" "F.Mask" "F.Paste")
			(net 26 "+1V8")
			(pinfunction "VCCO_32")
			(pintype "passive")
			(solder_mask_margin 0.02)
		)
		(pad "AB17" smd circle
			(at 1.5 6.5)
			(size 0.5 0.5)
			(property pad_prop_bga)
			(layers "F.Cu" "F.Mask" "F.Paste")
			(net 588 "unconnected-(U1D-IO_L18P_T2_32-PadAB17)")
			(pinfunction "IO_L18P_T2_32")
			(pintype "bidirectional+no_connect")
			(die_length 20.845)
			(solder_mask_margin 0.02)
		)
		(pad "AB18" smd circle
			(at 2.5 6.5)
			(size 0.5 0.5)
			(property pad_prop_bga)
			(layers "F.Cu" "F.Mask" "F.Paste")
			(net 589 "/FPGA Bank 18 & 32/ETH_RMII.MDC")
			(pinfunction "IO_L16N_T2_32")
			(pintype "bidirectional")
			(die_length 21.634)
			(solder_mask_margin 0.02)
		)
		(pad "AB19" smd circle
			(at 3.5 6.5)
			(size 0.5 0.5)
			(property pad_prop_bga)
			(layers "F.Cu" "F.Mask" "F.Paste")
			(net 590 "unconnected-(U1D-IO_L17P_T2_32-PadAB19)")
			(pinfunction "IO_L17P_T2_32")
			(pintype "bidirectional+no_connect")
			(die_length 21.895)
			(solder_mask_margin 0.02)
		)
		(pad "AB20" smd circle
			(at 4.5 6.5)
			(size 0.5 0.5)
			(property pad_prop_bga)
			(layers "F.Cu" "F.Mask" "F.Paste")
			(net 1356 "/SUP_MCU.A18")
			(pinfunction "IO_L6N_T0_VREF_12")
			(pintype "bidirectional")
			(die_length 4.931)
			(solder_mask_margin 0.02)
		)
		(pad "AB21" smd circle
			(at 5.5 6.5)
			(size 0.5 0.5)
			(property pad_prop_bga)
			(layers "F.Cu" "F.Mask" "F.Paste")
			(net 1 "GND")
			(pinfunction "GND")
			(pintype "passive")
			(solder_mask_margin 0.02)
		)
		(pad "AB22" smd circle
			(at 6.5 6.5)
			(size 0.5 0.5)
			(property pad_prop_bga)
			(layers "F.Cu" "F.Mask" "F.Paste")
			(net 1370 "/SUP_MCU.A11")
			(pinfunction "IO_L3P_T0_DQS_12")
			(pintype "bidirectional")
			(die_length 7.838)
			(solder_mask_margin 0.02)
		)
		(pad "AB23" smd circle
			(at 7.5 6.5)
			(size 0.5 0.5)
			(property pad_prop_bga)
			(layers "F.Cu" "F.Mask" "F.Paste")
			(net 1373 "/SUP_MCU.D3")
			(pinfunction "IO_L3N_T0_DQS_12")
			(pintype "bidirectional")
			(die_length 8.178)
			(solder_mask_margin 0.02)
		)
		(pad "AB24" smd circle
			(at 8.5 6.5)
			(size 0.5 0.5)
			(property pad_prop_bga)
			(layers "F.Cu" "F.Mask" "F.Paste")
			(net 1388 "/SUP_MCU.WR")
			(pinfunction "IO_L7P_T1_12")
			(pintype "bidirectional")
			(die_length 8.112)
			(solder_mask_margin 0.02)
		)
		(pad "AB25" smd circle
			(at 9.5 6.5)
			(size 0.5 0.5)
			(property pad_prop_bga)
			(layers "F.Cu" "F.Mask" "F.Paste")
			(net 453 "/FPGA Bank 12 & 13/PMOD_B.IO10")
			(pinfunction "IO_L6N_T0_VREF_13")
			(pintype "bidirectional")
			(die_length 11.623)
			(solder_mask_margin 0.02)
		)
		(pad "AB26" smd circle
			(at 10.5 6.5)
			(size 0.5 0.5)
			(property pad_prop_bga)
			(layers "F.Cu" "F.Mask" "F.Paste")
			(net 24 "+3V3")
			(pinfunction "VCCO_13")
			(pintype "passive")
			(solder_mask_margin 0.02)
		)
		(pad "AB27" smd circle
			(at 11.5 6.5)
			(size 0.5 0.5)
			(property pad_prop_bga)
			(layers "F.Cu" "F.Mask" "F.Paste")
			(net 1402 "/PLL.CLK2")
			(pinfunction "IO_L12P_T1_MRCC_13")
			(pintype "bidirectional")
			(die_length 15.547)
			(solder_mask_margin 0.02)
		)
		(pad "AB28" smd circle
			(at 12.5 6.5)
			(size 0.5 0.5)
			(property pad_prop_bga)
			(layers "F.Cu" "F.Mask" "F.Paste")
			(net 1307 "/USER_IO.LED_BLUE")
			(pinfunction "IO_L5N_T0_13")
			(pintype "bidirectional")
			(die_length 14.753)
			(solder_mask_margin 0.02)
		)
		(pad "AB29" smd circle
			(at 13.5 6.5)
			(size 0.5 0.5)
			(property pad_prop_bga)
			(layers "F.Cu" "F.Mask" "F.Paste")
			(net 470 "/FPGA Bank 12 & 13/PMOD_B.IO2")
			(pinfunction "IO_L10P_T1_13")
			(pintype "bidirectional")
			(die_length 17.569)
			(solder_mask_margin 0.02)
		)
		(pad "AB30" smd circle
			(at 14.5 6.5)
			(size 0.5 0.5)
			(property pad_prop_bga)
			(layers "F.Cu" "F.Mask" "F.Paste")
			(net 462 "/FPGA Bank 12 & 13/PMOD_B.IO1")
			(pinfunction "IO_L10N_T1_13")
			(pintype "bidirectional")
			(die_length 19.386)
			(solder_mask_margin 0.02)
		)
		(pad "AC1" smd circle
			(at -14.5 7.5)
			(size 0.5 0.5)
			(property pad_prop_bga)
			(layers "F.Cu" "F.Mask" "F.Paste")
			(net 543 "/DRAM + SRAM/DDR.A12")
			(pinfunction "IO_L2N_T0_34")
			(pintype "bidirectional")
			(die_length 18.921)
			(solder_mask_margin 0.02)
		)
		(pad "AC2" smd circle
			(at -13.5 7.5)
			(size 0.5 0.5)
			(property pad_prop_bga)
			(layers "F.Cu" "F.Mask" "F.Paste")
			(net 544 "/DRAM + SRAM/DDR.A13")
			(pinfunction "IO_L2P_T0_34")
			(pintype "bidirectional")
			(die_length 17.032)
			(solder_mask_margin 0.02)
		)
		(pad "AC3" smd circle
			(at -12.5 7.5)
			(size 0.5 0.5)
			(property pad_prop_bga)
			(layers "F.Cu" "F.Mask" "F.Paste")
			(net 25 "+1V35")
			(pinfunction "VCCO_34")
			(pintype "bidirectional")
			(solder_mask_margin 0.02)
		)
		(pad "AC4" smd circle
			(at -11.5 7.5)
			(size 0.5 0.5)
			(property pad_prop_bga)
			(layers "F.Cu" "F.Mask" "F.Paste")
			(net 541 "/DRAM + SRAM/DDR.A10")
			(pinfunction "IO_L4N_T0_34")
			(pintype "bidirectional")
			(die_length 17.452)
			(solder_mask_margin 0.02)
		)
		(pad "AC5" smd circle
			(at -10.5 7.5)
			(size 0.5 0.5)
			(property pad_prop_bga)
			(layers "F.Cu" "F.Mask" "F.Paste")
			(net 542 "/DRAM + SRAM/DDR.A11")
			(pinfunction "IO_L4P_T0_34")
			(pintype "bidirectional")
			(die_length 16.757)
			(solder_mask_margin 0.02)
		)
		(pad "AC6" smd circle
			(at -9.5 7.5)
			(size 0.5 0.5)
			(property pad_prop_bga)
			(layers "F.Cu" "F.Mask" "F.Paste")
			(net 567 "/FPGA Bank 33 & 34/DDR_VRN")
			(pinfunction "IO_0_VRN_34")
			(pintype "bidirectional")
			(die_length 18.428)
			(solder_mask_margin 0.02)
		)
		(pad "AC7" smd circle
			(at -8.5 7.5)
			(size 0.5 0.5)
			(property pad_prop_bga)
			(layers "F.Cu" "F.Mask" "F.Paste")
			(net 538 "/DRAM + SRAM/DDR.A7")
			(pinfunction "IO_L6P_T0_34")
			(pintype "bidirectional")
			(die_length 17.548)
			(solder_mask_margin 0.02)
		)
		(pad "AC8" smd circle
			(at -7.5 7.5)
			(size 0.5 0.5)
			(property pad_prop_bga)
			(layers "F.Cu" "F.Mask" "F.Paste")
			(net 1 "GND")
			(pinfunction "GND")
			(pintype "passive")
			(solder_mask_margin 0.02)
		)
		(pad "AC9" smd circle
			(at -6.5 7.5)
			(size 0.5 0.5)
			(property pad_prop_bga)
			(layers "F.Cu" "F.Mask" "F.Paste")
			(net 1308 "/USER_IO.DIP_SW3")
			(pinfunction "IO_L3N_T0_DQS_33")
			(pintype "bidirectional")
			(die_length 11.56)
			(solder_mask_margin 0.02)
		)
		(pad "AC10" smd circle
			(at -5.5 7.5)
			(size 0.5 0.5)
			(property pad_prop_bga)
			(layers "F.Cu" "F.Mask" "F.Paste")
			(net 393 "/FPGA Bank 33 & 34/SD_CARD.CMD")
			(pinfunction "IO_L7N_T1_33")
			(pintype "bidirectional")
			(die_length 12.11)
			(solder_mask_margin 0.02)
		)
		(pad "AC11" smd circle
			(at -4.5 7.5)
			(size 0.5 0.5)
			(property pad_prop_bga)
			(layers "F.Cu" "F.Mask" "F.Paste")
			(net 394 "/FPGA Bank 33 & 34/SD_CARD.CLK")
			(pinfunction "IO_L9N_T1_DQS_33")
			(pintype "bidirectional")
			(die_length 14.841)
			(solder_mask_margin 0.02)
		)
		(pad "AC12" smd circle
			(at -3.5 7.5)
			(size 0.5 0.5)
			(property pad_prop_bga)
			(layers "F.Cu" "F.Mask" "F.Paste")
			(net 406 "unconnected-(U1E-IO_L9P_T1_DQS_33-PadAC12)")
			(pinfunction "IO_L9P_T1_DQS_33")
			(pintype "bidirectional+no_connect")
			(die_length 14.948)
			(solder_mask_margin 0.02)
		)
		(pad "AC13" smd circle
			(at -2.5 7.5)
			(size 0.5 0.5)
			(property pad_prop_bga)
			(layers "F.Cu" "F.Mask" "F.Paste")
			(net 26 "+1V8")
			(pinfunction "VCCO_33")
			(pintype "passive")
			(solder_mask_margin 0.02)
		)
		(pad "AC14" smd circle
			(at -1.5 7.5)
			(size 0.5 0.5)
			(property pad_prop_bga)
			(layers "F.Cu" "F.Mask" "F.Paste")
			(net 601 "unconnected-(U1D-IO_L22P_T3_32-PadAC14)")
			(pinfunction "IO_L22P_T3_32")
			(pintype "bidirectional+no_connect")
			(die_length 12.461)
			(solder_mask_margin 0.02)
		)
		(pad "AC15" smd circle
			(at -0.5 7.5)
			(size 0.5 0.5)
			(property pad_prop_bga)
			(layers "F.Cu" "F.Mask" "F.Paste")
			(net 513 "/FPGA Bank 18 & 32/ETH_RMII.TXD0")
			(pinfunction "IO_L21N_T3_DQS_32")
			(pintype "bidirectional")
			(die_length 14.881)
			(solder_mask_margin 0.02)
		)
		(pad "AC16" smd circle
			(at 0.5 7.5)
			(size 0.5 0.5)
			(property pad_prop_bga)
			(layers "F.Cu" "F.Mask" "F.Paste")
			(net 602 "unconnected-(U1D-IO_L21P_T3_DQS_32-PadAC16)")
			(pinfunction "IO_L21P_T3_DQS_32")
			(pintype "bidirectional+no_connect")
			(die_length 15.421)
			(solder_mask_margin 0.02)
		)
		(pad "AC17" smd circle
			(at 1.5 7.5)
			(size 0.5 0.5)
			(property pad_prop_bga)
			(layers "F.Cu" "F.Mask" "F.Paste")
			(net 516 "/FPGA Bank 18 & 32/ETH_RMII.REFCLK")
			(pinfunction "IO_L18N_T2_32")
			(pintype "bidirectional")
			(die_length 20.722)
			(solder_mask_margin 0.02)
		)
		(pad "AC18" smd circle
			(at 2.5 7.5)
			(size 0.5 0.5)
			(property pad_prop_bga)
			(layers "F.Cu" "F.Mask" "F.Paste")
			(net 1 "GND")
			(pinfunction "GND")
			(pintype "passive")
			(solder_mask_margin 0.02)
		)
		(pad "AC19" smd circle
			(at 3.5 7.5)
			(size 0.5 0.5)
			(property pad_prop_bga)
			(layers "F.Cu" "F.Mask" "F.Paste")
			(net 519 "/FPGA Bank 18 & 32/ETH_RMII.RXD0")
			(pinfunction "IO_L17N_T2_32")
			(pintype "bidirectional")
			(die_length 20.941)
			(solder_mask_margin 0.02)
		)
		(pad "AC20" smd circle
			(at 4.5 7.5)
			(size 0.5 0.5)
			(property pad_prop_bga)
			(layers "F.Cu" "F.Mask" "F.Paste")
			(net 1374 "/SUP_MCU.D6")
			(pinfunction "IO_L5P_T0_12")
			(pintype "bidirectional")
			(die_length 6.323)
			(solder_mask_margin 0.02)
		)
		(pad "AC21" smd circle
			(at 5.5 7.5)
			(size 0.5 0.5)
			(property pad_prop_bga)
			(layers "F.Cu" "F.Mask" "F.Paste")
			(net 1380 "/SUP_MCU.D5")
			(pinfunction "IO_L5N_T0_12")
			(pintype "bidirectional")
			(die_length 5.293)
			(solder_mask_margin 0.02)
		)
		(pad "AC22" smd circle
			(at 6.5 7.5)
			(size 0.5 0.5)
			(property pad_prop_bga)
			(layers "F.Cu" "F.Mask" "F.Paste")
			(net 1369 "/SUP_MCU.A10")
			(pinfunction "IO_L8P_T1_12")
			(pintype "bidirectional")
			(die_length 7.349)
			(solder_mask_margin 0.02)
		)
		(pad "AC23" smd circle
			(at 7.5 7.5)
			(size 0.5 0.5)
			(property pad_prop_bga)
			(layers "F.Cu" "F.Mask" "F.Paste")
			(net 24 "+3V3")
			(pinfunction "VCCO_12")
			(pintype "bidirectional")
			(solder_mask_margin 0.02)
		)
		(pad "AC24" smd circle
			(at 8.5 7.5)
			(size 0.5 0.5)
			(property pad_prop_bga)
			(layers "F.Cu" "F.Mask" "F.Paste")
			(net 1378 "/SUP_MCU.A8")
			(pinfunction "IO_L9P_T1_DQS_12")
			(pintype "bidirectional")
			(die_length 8.538)
			(solder_mask_margin 0.02)
		)
		(pad "AC25" smd circle
			(at 9.5 7.5)
			(size 0.5 0.5)
			(property pad_prop_bga)
			(layers "F.Cu" "F.Mask" "F.Paste")
			(net 1391 "/SUP_MCU.A9")
			(pinfunction "IO_L7N_T1_12")
			(pintype "bidirectional")
			(die_length 9.609)
			(solder_mask_margin 0.02)
		)
		(pad "AC26" smd circle
			(at 10.5 7.5)
			(size 0.5 0.5)
			(property pad_prop_bga)
			(layers "F.Cu" "F.Mask" "F.Paste")
			(net 603 "unconnected-(U1A-IO_L19P_T3_13-PadAC26)")
			(pinfunction "IO_L19P_T3_13")
			(pintype "bidirectional+no_connect")
			(die_length 13.896)
			(solder_mask_margin 0.02)
		)
		(pad "AC27" smd circle
			(at 11.5 7.5)
			(size 0.5 0.5)
			(property pad_prop_bga)
			(layers "F.Cu" "F.Mask" "F.Paste")
			(net 604 "unconnected-(U1A-IO_L12N_T1_MRCC_13-PadAC27)")
			(pinfunction "IO_L12N_T1_MRCC_13")
			(pintype "bidirectional+no_connect")
			(die_length 15.768)
			(solder_mask_margin 0.02)
		)
		(pad "AC28" smd circle
			(at 12.5 7.5)
			(size 0.5 0.5)
			(property pad_prop_bga)
			(layers "F.Cu" "F.Mask" "F.Paste")
			(net 1 "GND")
			(pinfunction "GND")
			(pintype "passive")
			(solder_mask_margin 0.02)
		)
		(pad "AC29" smd circle
			(at 13.5 7.5)
			(size 0.5 0.5)
			(property pad_prop_bga)
			(layers "F.Cu" "F.Mask" "F.Paste")
			(net 471 "/FPGA Bank 12 & 13/PMOD_B.IO3")
			(pinfunction "IO_L7P_T1_13")
			(pintype "bidirectional")
			(die_length 15.896)
			(solder_mask_margin 0.02)
		)
		(pad "AC30" smd circle
			(at 14.5 7.5)
			(size 0.5 0.5)
			(property pad_prop_bga)
			(layers "F.Cu" "F.Mask" "F.Paste")
			(net 452 "/FPGA Bank 12 & 13/PMOD_B.IO9")
			(pinfunction "IO_L7N_T1_13")
			(pintype "bidirectional")
			(die_length 17.582)
			(solder_mask_margin 0.02)
		)
		(pad "AD1" smd circle
			(at -14.5 8.5)
			(size 0.5 0.5)
			(property pad_prop_bga)
			(layers "F.Cu" "F.Mask" "F.Paste")
			(net 552 "/DRAM + SRAM/DDR.CK_N")
			(pinfunction "IO_L3N_T0_DQS_34")
			(pintype "bidirectional")
			(die_length 20.294)
			(solder_mask_margin 0.02)
		)
		(pad "AD2" smd circle
			(at -13.5 8.5)
			(size 0.5 0.5)
			(property pad_prop_bga)
			(layers "F.Cu" "F.Mask" "F.Paste")
			(net 551 "/DRAM + SRAM/DDR.CK_P")
			(pinfunction "IO_L3P_T0_DQS_34")
			(pintype "bidirectional")
			(die_length 20.014)
			(solder_mask_margin 0.02)
		)
	)
)
